# S9S_MB_2U (Grand Teton) — schematic netlist excerpt (pin names and nets, part order shuffled) for the footprints in the layout excerpt that follows; sources: Cadence DE-HDL packaged netlist, KiCad conversion of 03242023_DA0F0TMBIJ0_F0T_Motherboard_J_brd_V01_OCP.brd

PR3922  Q_RES  0 5% CHIP  pkg 0402LF  page 302 : A = HSC_FLT_TYPE_2 ; B = HSC_FLT_TYPE
R2550  Q_RES  0 5% CHIP  pkg 0402LF  page 284 : A = FM_PVCCFA_EHV_FIVRA_CPU1_EN ; B = PVCCFA_EHV_FIVRA_CPU1_EN_R
PC1227  Q_CAPP  560UF 2.5V 20% OSCON  pkg THLF  page 262 : A = P1V05_PCH_AUX ; B = GND

(kicad_pcb
	(version 20260206)
	(generator "pcbnew")
	(generator_version "10.0")
	(general
		(thickness 1.6)
		(legacy_teardrops no)
	)
	(paper "A4")
	(title_block
		(title "03242023_DA0F0TMBIJ0_F0T_Motherboard_J_brd_V01_OCP.brd")
		(comment 1 "Grand Teton / footprints 2551-2553 of 6105")
	)
	(layers
		(0 "F.Cu" signal "TOP")
		(4 "In1.Cu" signal "GND")
		(6 "In2.Cu" signal "IN1")
		(8 "In3.Cu" signal "GND1")
		(10 "In4.Cu" signal "IN2")
		(12 "In5.Cu" signal "GND2")
		(14 "In6.Cu" signal "IN3")
		(16 "In7.Cu" signal "GND3")
		(18 "In8.Cu" signal "VCC")
		(20 "In9.Cu" signal "VCC1")
		(22 "In10.Cu" signal "GND4")
		(24 "In11.Cu" signal "IN4")
		(26 "In12.Cu" signal "GND5")
		(28 "In13.Cu" signal "IN5")
		(30 "In14.Cu" signal "GND6")
		(32 "In15.Cu" signal "IN6")
		(34 "In16.Cu" signal "GND7")
		(2 "B.Cu" signal "BOTTOM")
		(9 "F.Adhes" user "F.Adhesive")
		(11 "B.Adhes" user "B.Adhesive")
		(13 "F.Paste" user "Package Geometry/Pastemask Top")
		(15 "B.Paste" user "Package Geometry/Pastemask Bottom")
		(5 "F.SilkS" user "Ref Des/Silkscreen Top")
		(7 "B.SilkS" user "Ref Des/Silkscreen Bottom")
		(1 "F.Mask" user "Board Geometry/Soldermask Top")
		(3 "B.Mask" user "Board Geometry/Soldermask Bottom")
		(17 "Dwgs.User" user "User.Drawings")
		(19 "Cmts.User" user "User.Comments")
		(21 "Eco1.User" user "User.Eco1")
		(23 "Eco2.User" user "User.Eco2")
		(25 "Edge.Cuts" user "Board Geometry/Outline")
		(27 "Margin" user)
		(31 "F.CrtYd" user "Package Geometry/Place Bound Top")
		(29 "B.CrtYd" user "Package Geometry/Place Bound Bottom")
		(35 "F.Fab" user "Ref Des/Assembly Top")
		(33 "B.Fab" user "Ref Des/Assembly Bottom")
	)
	(footprint ""
		(layer "F.Cu")
		(at 102.827074 -354.847652)
		(property "Reference" "R2550"
			(at 0 0 0)
			(layer "F.SilkS")
			(hide yes)
			(effects
				(font
					(size 1.27 1.27)
				)
			)
		)
		(property "Value" ""
			(at 0 0 0)
			(layer "F.Fab")
			(effects
				(font
					(size 1.27 1.27)
				)
			)
		)
		(duplicate_pad_numbers_are_jumpers no)
		(fp_line
			(start -0.7874 -0.4064)
			(end 0.7874 -0.4064)
			(stroke
				(width 0.1524)
				(type default)
			)
			(layer "F.SilkS")
		)
		(fp_line
			(start -0.7874 0.4064)
			(end -0.7874 -0.4064)
			(stroke
				(width 0.1524)
				(type default)
			)
			(layer "F.SilkS")
		)
		(fp_line
			(start 0.7874 -0.4064)
			(end 0.7874 0.4064)
			(stroke
				(width 0.1524)
				(type default)
			)
			(layer "F.SilkS")
		)
		(fp_line
			(start 0.7874 0.4064)
			(end -0.7874 0.4064)
			(stroke
				(width 0.1524)
				(type default)
			)
			(layer "F.SilkS")
		)
		(fp_line
			(start -0.67945 -0.305054)
			(end -0.12065 -0.305054)
			(stroke
				(width 0.1)
				(type default)
			)
			(layer "F.Fab")
		)
		(fp_line
			(start -0.67945 0.3048)
			(end -0.67945 -0.305054)
			(stroke
				(width 0.1)
				(type default)
			)
			(layer "F.Fab")
		)
		(fp_line
			(start -0.12065 -0.305054)
			(end -0.12065 -0.2794)
			(stroke
				(width 0.1)
				(type default)
			)
			(layer "F.Fab")
		)
		(fp_line
			(start -0.12065 -0.2794)
			(end 0.12065 -0.2794)
			(stroke
				(width 0.1)
				(type default)
			)
			(layer "F.Fab")
		)
		(fp_line
			(start -0.12065 0.2794)
			(end -0.12065 0.3048)
			(stroke
				(width 0.1)
				(type default)
			)
			(layer "F.Fab")
		)
		(fp_line
			(start -0.12065 0.3048)
			(end -0.67945 0.3048)
			(stroke
				(width 0.1)
				(type default)
			)
			(layer "F.Fab")
		)
		(fp_line
			(start 0.120396 0.2794)
			(end -0.12065 0.2794)
			(stroke
				(width 0.1)
				(type default)
			)
			(layer "F.Fab")
		)
		(fp_line
			(start 0.120396 0.3048)
			(end 0.120396 0.2794)
			(stroke
				(width 0.1)
				(type default)
			)
			(layer "F.Fab")
		)
		(fp_line
			(start 0.12065 -0.3048)
			(end 0.67945 -0.3048)
			(stroke
				(width 0.1)
				(type default)
			)
			(layer "F.Fab")
		)
		(fp_line
			(start 0.12065 -0.2794)
			(end 0.12065 -0.3048)
			(stroke
				(width 0.1)
				(type default)
			)
			(layer "F.Fab")
		)
		(fp_line
			(start 0.67945 -0.3048)
			(end 0.67945 0.3048)
			(stroke
				(width 0.1)
				(type default)
			)
			(layer "F.Fab")
		)
		(fp_line
			(start 0.67945 0.3048)
			(end 0.120396 0.3048)
			(stroke
				(width 0.1)
				(type default)
			)
			(layer "F.Fab")
		)
		(pad "1" smd circle
			(at -0.40005 0)
			(size 0 0)
			(layers "F.Cu" "F.Mask" "F.Paste")
			(net "FM_PVCCFA_EHV_FIVRA_CPU1_EN")
		)
		(pad "2" smd circle
			(at 0.40005 0)
			(size 0 0)
			(layers "F.Cu" "F.Mask" "F.Paste")
			(net "PVCCFA_EHV_FIVRA_CPU1_EN_R")
		)
	)
	(footprint ""
		(layer "F.Cu")
		(at 279.6032 -65.877948)
		(property "Reference" "PC1227"
			(at 0 0 0)
			(layer "F.SilkS")
			(hide yes)
			(effects
				(font
					(size 1.27 1.27)
				)
			)
		)
		(property "Value" ""
			(at 0 0 0)
			(layer "F.Fab")
			(effects
				(font
					(size 1.27 1.27)
				)
			)
		)
		(duplicate_pad_numbers_are_jumpers no)
		(fp_line
			(start 2.750058 0.999998)
			(end -2.750058 0.999998)
			(stroke
				(width 0.1524)
				(type default)
			)
			(layer "F.SilkS")
		)
		(fp_circle
			(center 0 0.999998)
			(end 2.750058 0.999998)
			(stroke
				(width 0.1524)
				(type default)
			)
			(fill no)
			(layer "F.SilkS")
		)
		(fp_poly
			(pts
				(arc
					(start 2.750058 0.999998)
					(mid 0 3.750056)
					(end -2.750058 0.999998)
				)
			)
			(stroke
				(width 0)
				(type default)
			)
			(fill yes)
			(layer "F.SilkS")
		)
		(fp_circle
			(center 0 0.999998)
			(end 2.750058 0.999998)
			(stroke
				(width 0.1)
				(type default)
			)
			(fill no)
			(layer "F.Fab")
		)
		(pad "1" thru_hole rect
			(at 0 0)
			(size 1.5748 1.5748)
			(drill 1.0668)
			(layers "*.Cu" "*.Mask")
			(remove_unused_layers no)
			(net "P1V05_PCH_AUX")
			(clearance 0)
			(padstack
				(mode front_inner_back)
				(layer "Inner"
					(shape circle)
					(size 1.5748 1.5748)
					(clearance 0)
				)
				(layer "B.Cu"
					(shape rect)
					(size 1.5748 1.5748)
					(clearance 0)
				)
			)
		)
		(pad "2" thru_hole circle
			(at 0 1.999996)
			(size 1.5748 1.5748)
			(drill 1.0668)
			(layers "*.Cu" "*.Mask")
			(remove_unused_layers no)
			(net "GND")
			(clearance 0)
		)
	)
	(footprint ""
		(layer "F.Cu")
		(at 216.065608 -406.855422)
		(property "Reference" "PR3922"
			(at 0 0 0)
			(layer "F.SilkS")
			(hide yes)
			(effects
				(font
					(size 1.27 1.27)
				)
			)
		)
		(property "Value" ""
			(at 0 0 0)
			(layer "F.Fab")
			(effects
				(font
					(size 1.27 1.27)
				)
			)
		)
		(duplicate_pad_numbers_are_jumpers no)
		(fp_line
			(start -0.7874 -0.4064)
			(end 0.7874 -0.4064)
			(stroke
				(width 0.1524)
				(type default)
			)
			(layer "F.SilkS")
		)
		(fp_line
			(start -0.7874 0.4064)
			(end -0.7874 -0.4064)
			(stroke
				(width 0.1524)
				(type default)
			)
			(layer "F.SilkS")
		)
		(fp_line
			(start 0.7874 -0.4064)
			(end 0.7874 0.4064)
			(stroke
				(width 0.1524)
				(type default)
			)
			(layer "F.SilkS")
		)
		(fp_line
			(start 0.7874 0.4064)
			(end -0.7874 0.4064)
			(stroke
				(width 0.1524)
				(type default)
			)
			(layer "F.SilkS")
		)
		(fp_line
			(start -0.67945 -0.305054)
			(end -0.12065 -0.305054)
			(stroke
				(width 0.1)
				(type default)
			)
			(layer "F.Fab")
		)
		(fp_line
			(start -0.67945 0.3048)
			(end -0.67945 -0.305054)
			(stroke
				(width 0.1)
				(type default)
			)
			(layer "F.Fab")
		)
		(fp_line
			(start -0.12065 -0.305054)
			(end -0.12065 -0.2794)
			(stroke
				(width 0.1)
				(type default)
			)
			(layer "F.Fab")
		)
		(fp_line
			(start -0.12065 -0.2794)
			(end 0.12065 -0.2794)
			(stroke
				(width 0.1)
				(type default)
			)
			(layer "F.Fab")
		)
		(fp_line
			(start -0.12065 0.2794)
			(end -0.12065 0.3048)
			(stroke
				(width 0.1)
				(type default)
			)
			(layer "F.Fab")
		)
		(fp_line
			(start -0.12065 0.3048)
			(end -0.67945 0.3048)
			(stroke
				(width 0.1)
				(type default)
			)
			(layer "F.Fab")
		)
		(fp_line
			(start 0.120396 0.2794)
			(end -0.12065 0.2794)
			(stroke
				(width 0.1)
				(type default)
			)
			(layer "F.Fab")
		)
		(fp_line
			(start 0.120396 0.3048)
			(end 0.120396 0.2794)
			(stroke
				(width 0.1)
				(type default)
			)
			(layer "F.Fab")
		)
		(fp_line
			(start 0.12065 -0.3048)
			(end 0.67945 -0.3048)
			(stroke
				(width 0.1)
				(type default)
			)
			(layer "F.Fab")
		)
		(fp_line
			(start 0.12065 -0.2794)
			(end 0.12065 -0.3048)
			(stroke
				(width 0.1)
				(type default)
			)
			(layer "F.Fab")
		)
		(fp_line
			(start 0.67945 -0.3048)
			(end 0.67945 0.3048)
			(stroke
				(width 0.1)
				(type default)
			)
			(layer "F.Fab")
		)
		(fp_line
			(start 0.67945 0.3048)
			(end 0.120396 0.3048)
			(stroke
				(width 0.1)
				(type default)
			)
			(layer "F.Fab")
		)
		(pad "1" smd circle
			(at -0.40005 0)
			(size 0 0)
			(layers "F.Cu" "F.Mask" "F.Paste")
			(net "HSC_FLT_TYPE_2")
		)
		(pad "2" smd circle
			(at 0.40005 0)
			(size 0 0)
			(layers "F.Cu" "F.Mask" "F.Paste")
			(net "HSC_FLT_TYPE")
		)
	)
)
